(kicad_pcb
	(version 20260206)
	(generator "pcbnew")
	(generator_version "10.0")
	(general
		(thickness 1.6)
		(legacy_teardrops no)
	)
	(paper "A4")
	(title_block
		(title "Bryce Canyon_SCC_16316-1_OCP.brd")
		(comment 1 "Bryce Canyon / footprints 792-799 of 1561")
	)
	(layers
		(0 "F.Cu" signal "TOP")
		(4 "In1.Cu" signal "L2GND")
		(6 "In2.Cu" signal "L3")
		(8 "In3.Cu" signal "L4VCC")
		(10 "In4.Cu" signal "L5VCC")
		(12 "In5.Cu" signal "L6")
		(14 "In6.Cu" signal "L7GND")
		(2 "B.Cu" signal "BOTTOM")
		(9 "F.Adhes" user "F.Adhesive")
		(11 "B.Adhes" user "B.Adhesive")
		(13 "F.Paste" user "Package Geometry/Pastemask Top")
		(15 "B.Paste" user "Package Geometry/Pastemask Bottom")
		(5 "F.SilkS" user "Ref Des/Silkscreen Top")
		(7 "B.SilkS" user "Ref Des/Silkscreen Bottom")
		(1 "F.Mask" user "Board Geometry/Soldermask Top")
		(3 "B.Mask" user "Board Geometry/Soldermask Bottom")
		(17 "Dwgs.User" user "User.Drawings")
		(19 "Cmts.User" user "User.Comments")
		(21 "Eco1.User" user "User.Eco1")
		(23 "Eco2.User" user "User.Eco2")
		(25 "Edge.Cuts" user "Board Geometry/Outline")
		(27 "Margin" user)
		(31 "F.CrtYd" user "Package Geometry/Place Bound Top")
		(29 "B.CrtYd" user "Package Geometry/Place Bound Bottom")
		(35 "F.Fab" user "Ref Des/Assembly Top")
		(33 "B.Fab" user "Ref Des/Assembly Bottom")
	)
	(footprint ""
		(layer "B.Cu")
		(at 177.254408 -49.50333 -90)
		(property "Reference" "C497"
			(at 0 0 90)
			(layer "B.SilkS")
			(hide yes)
			(effects
				(font
					(size 1.27 1.27)
				)
				(justify mirror)
			)
		)
		(property "Value" "SC1KP50V2KX-1GP"
			(at -1.1811 -2.7051 270)
			(unlocked yes)
			(layer "B.Fab")
			(hide yes)
			(effects
				(font
					(size 1.016 1.016)
					(thickness 0.1524)
				)
				(justify mirror)
			)
		)
		(property "Device Type" "C402H22"
			(at -1.1811 -4.2291 270)
			(unlocked yes)
			(layer "B.Fab")
			(hide yes)
			(effects
				(font
					(size 1.016 1.016)
					(thickness 0.1524)
				)
				(justify mirror)
			)
		)
		(duplicate_pad_numbers_are_jumpers no)
		(fp_rect
			(start 0.4318 0.9525)
			(end -0.4318 -0.9525)
			(stroke
				(width 0)
				(type default)
			)
			(fill no)
			(layer "B.CrtYd")
		)
		(fp_rect
			(start 0.4318 0.9525)
			(end -0.4318 -0.9525)
			(stroke
				(width 0)
				(type default)
			)
			(fill no)
			(layer "B.Fab")
		)
		(pad "1" smd custom
			(at 0 -0.4445 90)
			(size 0.1524 0.1524)
			(layers "B.Cu" "B.Mask" "B.Paste")
			(net "P1V8_C")
			(options
				(clearance outline)
				(anchor circle)
			)
			(primitives
				(gr_poly
					(pts
						(arc
							(start 0.3048 0.2032)
							(mid 0.275042 0.275042)
							(end 0.2032 0.3048)
						)
						(arc
							(start -0.2032 0.3048)
							(mid -0.275042 0.275042)
							(end -0.3048 0.2032)
						)
						(arc
							(start -0.3048 -0.2032)
							(mid -0.275042 -0.275042)
							(end -0.2032 -0.3048)
						)
						(arc
							(start 0.2032 -0.3048)
							(mid 0.275042 -0.275042)
							(end 0.3048 -0.2032)
						)
					)
					(width 0)
					(fill yes)
				)
			)
		)
		(pad "2" smd custom
			(at 0 0.4445 90)
			(size 0.1524 0.1524)
			(layers "B.Cu" "B.Mask" "B.Paste")
			(net "GND")
			(options
				(clearance outline)
				(anchor circle)
			)
			(primitives
				(gr_poly
					(pts
						(arc
							(start 0.3048 0.2032)
							(mid 0.275042 0.275042)
							(end 0.2032 0.3048)
						)
						(arc
							(start -0.2032 0.3048)
							(mid -0.275042 0.275042)
							(end -0.3048 0.2032)
						)
						(arc
							(start -0.3048 -0.2032)
							(mid -0.275042 -0.275042)
							(end -0.2032 -0.3048)
						)
						(arc
							(start 0.2032 -0.3048)
							(mid 0.275042 -0.275042)
							(end 0.3048 -0.2032)
						)
					)
					(width 0)
					(fill yes)
				)
			)
		)
	)
	(footprint ""
		(layer "B.Cu")
		(at 158.8262 -27.178)
		(property "Reference" "L24"
			(at 0 0 0)
			(layer "B.SilkS")
			(hide yes)
			(effects
				(font
					(size 1.27 1.27)
				)
				(justify mirror)
			)
		)
		(property "Value" "MPZ2012S601AT-GP"
			(at 0 -4.2418 0)
			(unlocked yes)
			(layer "B.Fab")
			(hide yes)
			(effects
				(font
					(size 1.016 1.016)
					(thickness 0.1524)
				)
				(justify mirror)
			)
		)
		(property "Device Type" "L805H42"
			(at 0 -5.7912 0)
			(unlocked yes)
			(layer "B.Fab")
			(hide yes)
			(effects
				(font
					(size 1.016 1.016)
					(thickness 0.1524)
				)
				(justify mirror)
			)
		)
		(duplicate_pad_numbers_are_jumpers no)
		(fp_line
			(start -0.889 -1.7018)
			(end -0.889 1.7018)
			(stroke
				(width 0.1524)
				(type default)
			)
			(layer "B.SilkS")
		)
		(fp_line
			(start -0.889 1.7018)
			(end 0.889 1.7018)
			(stroke
				(width 0.1524)
				(type default)
			)
			(layer "B.SilkS")
		)
		(fp_line
			(start 0.889 -1.7018)
			(end -0.889 -1.7018)
			(stroke
				(width 0.1524)
				(type default)
			)
			(layer "B.SilkS")
		)
		(fp_line
			(start 0.889 1.7018)
			(end 0.889 -1.7018)
			(stroke
				(width 0.1524)
				(type default)
			)
			(layer "B.SilkS")
		)
		(fp_rect
			(start 0.9652 1.778)
			(end -0.9652 -1.778)
			(stroke
				(width 0)
				(type default)
			)
			(fill no)
			(layer "B.CrtYd")
		)
		(fp_rect
			(start 0.9652 1.778)
			(end -0.9652 -1.778)
			(stroke
				(width 0)
				(type default)
			)
			(fill no)
			(layer "B.Fab")
		)
		(pad "1" smd rect
			(at 0 -0.9652 180)
			(size 1.397 1.143)
			(layers "B.Cu" "B.Mask" "B.Paste")
			(net "SAS0_VDDH")
		)
		(pad "2" smd rect
			(at 0 0.9652 180)
			(size 1.397 1.143)
			(layers "B.Cu" "B.Mask" "B.Paste")
			(net "P1V8_C")
		)
	)
	(footprint ""
		(layer "B.Cu")
		(at 154.184604 -64.122808 -90)
		(property "Reference" "C355"
			(at 0 0 90)
			(layer "B.SilkS")
			(hide yes)
			(effects
				(font
					(size 1.27 1.27)
				)
				(justify mirror)
			)
		)
		(property "Value" "SC22U6D3V3MX-9-GP-U"
			(at 0 -2.8194 270)
			(unlocked yes)
			(layer "B.Fab")
			(hide yes)
			(effects
				(font
					(size 1.016 1.016)
					(thickness 0.1524)
				)
				(justify mirror)
			)
		)
		(property "Device Type" "C603H40"
			(at 0 -4.3434 270)
			(unlocked yes)
			(layer "B.Fab")
			(hide yes)
			(effects
				(font
					(size 1.016 1.016)
					(thickness 0.1524)
				)
				(justify mirror)
			)
		)
		(duplicate_pad_numbers_are_jumpers no)
		(fp_line
			(start -0.508 0)
			(end 0.508 0)
			(stroke
				(width 0.2032)
				(type default)
			)
			(layer "B.SilkS")
		)
		(fp_rect
			(start 0.5842 1.3335)
			(end -0.5842 -1.3335)
			(stroke
				(width 0)
				(type default)
			)
			(fill no)
			(layer "B.CrtYd")
		)
		(fp_rect
			(start 0.5842 1.3335)
			(end -0.5842 -1.3335)
			(stroke
				(width 0)
				(type default)
			)
			(fill no)
			(layer "B.Fab")
		)
		(pad "1" smd custom
			(at 0 -0.762 90)
			(size 0.2159 0.2159)
			(layers "B.Cu" "B.Mask" "B.Paste")
			(net "SYS_PLL_VDD")
			(options
				(clearance outline)
				(anchor circle)
			)
			(primitives
				(gr_poly
					(pts
						(arc
							(start -0.3302 0.4318)
							(mid -0.402042 0.402042)
							(end -0.4318 0.3302)
						)
						(arc
							(start -0.4318 -0.3302)
							(mid -0.402042 -0.402042)
							(end -0.3302 -0.4318)
						)
						(arc
							(start 0.3302 -0.4318)
							(mid 0.402042 -0.402042)
							(end 0.4318 -0.3302)
						)
						(arc
							(start 0.4318 0.3302)
							(mid 0.402042 0.402042)
							(end 0.3302 0.4318)
						)
					)
					(width 0)
					(fill yes)
				)
			)
		)
		(pad "2" smd custom
			(at 0 0.762 90)
			(size 0.2159 0.2159)
			(layers "B.Cu" "B.Mask" "B.Paste")
			(net "GND")
			(options
				(clearance outline)
				(anchor circle)
			)
			(primitives
				(gr_poly
					(pts
						(arc
							(start -0.3302 0.4318)
							(mid -0.402042 0.402042)
							(end -0.4318 0.3302)
						)
						(arc
							(start -0.4318 -0.3302)
							(mid -0.402042 -0.402042)
							(end -0.3302 -0.4318)
						)
						(arc
							(start 0.3302 -0.4318)
							(mid 0.402042 -0.402042)
							(end 0.4318 -0.3302)
						)
						(arc
							(start 0.4318 0.3302)
							(mid 0.402042 0.402042)
							(end 0.3302 0.4318)
						)
					)
					(width 0)
					(fill yes)
				)
			)
		)
	)
	(footprint ""
		(layer "B.Cu")
		(at 163.576 -52.07)
		(property "Reference" "R195"
			(at 0 0 0)
			(layer "B.SilkS")
			(hide yes)
			(effects
				(font
					(size 1.27 1.27)
				)
				(justify mirror)
			)
		)
		(property "Value" "2K2R2F-GP"
			(at -0.064008 -3.993896 0)
			(unlocked yes)
			(layer "B.Fab")
			(hide yes)
			(effects
				(font
					(size 1.016 1.016)
					(thickness 0.1524)
				)
				(justify mirror)
			)
		)
		(property "Device Type" "R402H16"
			(at -0.064008 -5.517896 0)
			(unlocked yes)
			(layer "B.Fab")
			(hide yes)
			(effects
				(font
					(size 1.016 1.016)
					(thickness 0.1524)
				)
				(justify mirror)
			)
		)
		(duplicate_pad_numbers_are_jumpers no)
		(fp_line
			(start -0.508 -0.9398)
			(end 0.508 -0.9398)
			(stroke
				(width 0.1524)
				(type default)
			)
			(layer "B.SilkS")
		)
		(fp_line
			(start 0.508 -0.9398)
			(end 0.508 0.9398)
			(stroke
				(width 0.1524)
				(type default)
			)
			(layer "B.SilkS")
		)
		(fp_rect
			(start 0.508 0.9398)
			(end -0.508 -0.9398)
			(stroke
				(width 0)
				(type default)
			)
			(fill no)
			(layer "B.CrtYd")
		)
		(fp_rect
			(start 0.508 0.9398)
			(end -0.508 -0.9398)
			(stroke
				(width 0)
				(type default)
			)
			(fill no)
			(layer "B.Fab")
		)
		(pad "1" smd custom
			(at 0 -0.4445 180)
			(size 0.1397 0.1397)
			(layers "B.Cu" "B.Mask" "B.Paste")
			(net "P1V8_C")
			(options
				(clearance outline)
				(anchor circle)
			)
			(primitives
				(gr_poly
					(pts
						(arc
							(start -0.1778 0.2794)
							(mid -0.249642 0.249642)
							(end -0.2794 0.1778)
						)
						(arc
							(start -0.2794 -0.1778)
							(mid -0.249642 -0.249642)
							(end -0.1778 -0.2794)
						)
						(arc
							(start 0.1778 -0.2794)
							(mid 0.249642 -0.249642)
							(end 0.2794 -0.1778)
						)
						(arc
							(start 0.2794 0.1778)
							(mid 0.249642 0.249642)
							(end 0.1778 0.2794)
						)
					)
					(width 0)
					(fill yes)
				)
			)
		)
		(pad "2" smd custom
			(at 0 0.4445 180)
			(size 0.1397 0.1397)
			(layers "B.Cu" "B.Mask" "B.Paste")
			(net "SIO_DOUT_0")
			(options
				(clearance outline)
				(anchor circle)
			)
			(primitives
				(gr_poly
					(pts
						(arc
							(start -0.1778 0.2794)
							(mid -0.249642 0.249642)
							(end -0.2794 0.1778)
						)
						(arc
							(start -0.2794 -0.1778)
							(mid -0.249642 -0.249642)
							(end -0.1778 -0.2794)
						)
						(arc
							(start 0.1778 -0.2794)
							(mid 0.249642 -0.249642)
							(end 0.2794 -0.1778)
						)
						(arc
							(start 0.2794 0.1778)
							(mid 0.249642 0.249642)
							(end 0.1778 0.2794)
						)
					)
					(width 0)
					(fill yes)
				)
			)
		)
	)
	(footprint ""
		(layer "B.Cu")
		(at 164.781992 -11.70813)
		(property "Reference" "C502"
			(at 0 0 0)
			(layer "B.SilkS")
			(hide yes)
			(effects
				(font
					(size 1.27 1.27)
				)
				(justify mirror)
			)
		)
		(property "Value" "SCD1U16V2KX-3GP"
			(at -1.1811 -2.7051 0)
			(unlocked yes)
			(layer "B.Fab")
			(hide yes)
			(effects
				(font
					(size 1.016 1.016)
					(thickness 0.1524)
				)
				(justify mirror)
			)
		)
		(property "Device Type" "C402H22"
			(at -1.1811 -4.2291 0)
			(unlocked yes)
			(layer "B.Fab")
			(hide yes)
			(effects
				(font
					(size 1.016 1.016)
					(thickness 0.1524)
				)
				(justify mirror)
			)
		)
		(duplicate_pad_numbers_are_jumpers no)
		(fp_rect
			(start 0.4318 0.9525)
			(end -0.4318 -0.9525)
			(stroke
				(width 0)
				(type default)
			)
			(fill no)
			(layer "B.CrtYd")
		)
		(fp_rect
			(start 0.4318 0.9525)
			(end -0.4318 -0.9525)
			(stroke
				(width 0)
				(type default)
			)
			(fill no)
			(layer "B.Fab")
		)
		(pad "1" smd custom
			(at 0 -0.4445 180)
			(size 0.1524 0.1524)
			(layers "B.Cu" "B.Mask" "B.Paste")
			(net "P3V3")
			(options
				(clearance outline)
				(anchor circle)
			)
			(primitives
				(gr_poly
					(pts
						(arc
							(start 0.3048 0.2032)
							(mid 0.275042 0.275042)
							(end 0.2032 0.3048)
						)
						(arc
							(start -0.2032 0.3048)
							(mid -0.275042 0.275042)
							(end -0.3048 0.2032)
						)
						(arc
							(start -0.3048 -0.2032)
							(mid -0.275042 -0.275042)
							(end -0.2032 -0.3048)
						)
						(arc
							(start 0.2032 -0.3048)
							(mid 0.275042 -0.275042)
							(end 0.3048 -0.2032)
						)
					)
					(width 0)
					(fill yes)
				)
			)
		)
		(pad "2" smd custom
			(at 0 0.4445 180)
			(size 0.1524 0.1524)
			(layers "B.Cu" "B.Mask" "B.Paste")
			(net "GND")
			(options
				(clearance outline)
				(anchor circle)
			)
			(primitives
				(gr_poly
					(pts
						(arc
							(start 0.3048 0.2032)
							(mid 0.275042 0.275042)
							(end 0.2032 0.3048)
						)
						(arc
							(start -0.2032 0.3048)
							(mid -0.275042 0.275042)
							(end -0.3048 0.2032)
						)
						(arc
							(start -0.3048 -0.2032)
							(mid -0.275042 -0.275042)
							(end -0.2032 -0.3048)
						)
						(arc
							(start 0.2032 -0.3048)
							(mid 0.275042 -0.275042)
							(end 0.3048 -0.2032)
						)
					)
					(width 0)
					(fill yes)
				)
			)
		)
	)
	(footprint ""
		(layer "B.Cu")
		(at 113.1316 -84.455)
		(property "Reference" "R139"
			(at 0 0 0)
			(layer "B.SilkS")
			(hide yes)
			(effects
				(font
					(size 1.27 1.27)
				)
				(justify mirror)
			)
		)
		(property "Value" "10KR2F-2-GP"
			(at -0.064008 -3.993896 0)
			(unlocked yes)
			(layer "B.Fab")
			(hide yes)
			(effects
				(font
					(size 1.016 1.016)
					(thickness 0.1524)
				)
				(justify mirror)
			)
		)
		(property "Device Type" "R402H16"
			(at -0.064008 -5.517896 0)
			(unlocked yes)
			(layer "B.Fab")
			(hide yes)
			(effects
				(font
					(size 1.016 1.016)
					(thickness 0.1524)
				)
				(justify mirror)
			)
		)
		(duplicate_pad_numbers_are_jumpers no)
		(fp_line
			(start -0.508 -0.9398)
			(end 0.508 -0.9398)
			(stroke
				(width 0.1524)
				(type default)
			)
			(layer "B.SilkS")
		)
		(fp_line
			(start 0.508 -0.9398)
			(end 0.508 0.9398)
			(stroke
				(width 0.1524)
				(type default)
			)
			(layer "B.SilkS")
		)
		(fp_rect
			(start 0.508 0.9398)
			(end -0.508 -0.9398)
			(stroke
				(width 0)
				(type default)
			)
			(fill no)
			(layer "B.CrtYd")
		)
		(fp_rect
			(start 0.508 0.9398)
			(end -0.508 -0.9398)
			(stroke
				(width 0)
				(type default)
			)
			(fill no)
			(layer "B.Fab")
		)
		(pad "1" smd custom
			(at 0 -0.4445 180)
			(size 0.1397 0.1397)
			(layers "B.Cu" "B.Mask" "B.Paste")
			(net "P1V8_E")
			(options
				(clearance outline)
				(anchor circle)
			)
			(primitives
				(gr_poly
					(pts
						(arc
							(start -0.1778 0.2794)
							(mid -0.249642 0.249642)
							(end -0.2794 0.1778)
						)
						(arc
							(start -0.2794 -0.1778)
							(mid -0.249642 -0.249642)
							(end -0.1778 -0.2794)
						)
						(arc
							(start 0.1778 -0.2794)
							(mid 0.249642 -0.249642)
							(end 0.2794 -0.1778)
						)
						(arc
							(start 0.2794 0.1778)
							(mid 0.249642 0.249642)
							(end 0.1778 0.2794)
						)
					)
					(width 0)
					(fill yes)
				)
			)
		)
		(pad "2" smd custom
			(at 0 0.4445 180)
			(size 0.1397 0.1397)
			(layers "B.Cu" "B.Mask" "B.Paste")
			(net "EXP_XM_CS_N_0")
			(options
				(clearance outline)
				(anchor circle)
			)
			(primitives
				(gr_poly
					(pts
						(arc
							(start -0.1778 0.2794)
							(mid -0.249642 0.249642)
							(end -0.2794 0.1778)
						)
						(arc
							(start -0.2794 -0.1778)
							(mid -0.249642 -0.249642)
							(end -0.1778 -0.2794)
						)
						(arc
							(start 0.1778 -0.2794)
							(mid 0.249642 -0.249642)
							(end 0.2794 -0.1778)
						)
						(arc
							(start 0.2794 0.1778)
							(mid 0.249642 0.249642)
							(end 0.1778 0.2794)
						)
					)
					(width 0)
					(fill yes)
				)
			)
		)
	)
	(footprint ""
		(layer "B.Cu")
		(at 184.87517 -49.663858 90)
		(property "Reference" "C499"
			(at 0 0 90)
			(layer "B.SilkS")
			(hide yes)
			(effects
				(font
					(size 1.27 1.27)
				)
				(justify mirror)
			)
		)
		(property "Value" "SC1KP50V2KX-1GP"
			(at -1.1811 -2.7051 90)
			(unlocked yes)
			(layer "B.Fab")
			(hide yes)
			(effects
				(font
					(size 1.016 1.016)
					(thickness 0.1524)
				)
				(justify mirror)
			)
		)
		(property "Device Type" "C402H22"
			(at -1.1811 -4.2291 90)
			(unlocked yes)
			(layer "B.Fab")
			(hide yes)
			(effects
				(font
					(size 1.016 1.016)
					(thickness 0.1524)
				)
				(justify mirror)
			)
		)
		(duplicate_pad_numbers_are_jumpers no)
		(fp_rect
			(start 0.4318 0.9525)
			(end -0.4318 -0.9525)
			(stroke
				(width 0)
				(type default)
			)
			(fill no)
			(layer "B.CrtYd")
		)
		(fp_rect
			(start 0.4318 0.9525)
			(end -0.4318 -0.9525)
			(stroke
				(width 0)
				(type default)
			)
			(fill no)
			(layer "B.Fab")
		)
		(pad "1" smd custom
			(at 0 -0.4445 270)
			(size 0.1524 0.1524)
			(layers "B.Cu" "B.Mask" "B.Paste")
			(net "P1V8_C")
			(options
				(clearance outline)
				(anchor circle)
			)
			(primitives
				(gr_poly
					(pts
						(arc
							(start 0.3048 0.2032)
							(mid 0.275042 0.275042)
							(end 0.2032 0.3048)
						)
						(arc
							(start -0.2032 0.3048)
							(mid -0.275042 0.275042)
							(end -0.3048 0.2032)
						)
						(arc
							(start -0.3048 -0.2032)
							(mid -0.275042 -0.275042)
							(end -0.2032 -0.3048)
						)
						(arc
							(start 0.2032 -0.3048)
							(mid 0.275042 -0.275042)
							(end 0.3048 -0.2032)
						)
					)
					(width 0)
					(fill yes)
				)
			)
		)
		(pad "2" smd custom
			(at 0 0.4445 270)
			(size 0.1524 0.1524)
			(layers "B.Cu" "B.Mask" "B.Paste")
			(net "GND")
			(options
				(clearance outline)
				(anchor circle)
			)
			(primitives
				(gr_poly
					(pts
						(arc
							(start 0.3048 0.2032)
							(mid 0.275042 0.275042)
							(end 0.2032 0.3048)
						)
						(arc
							(start -0.2032 0.3048)
							(mid -0.275042 0.275042)
							(end -0.3048 0.2032)
						)
						(arc
							(start -0.3048 -0.2032)
							(mid -0.275042 -0.275042)
							(end -0.2032 -0.3048)
						)
						(arc
							(start 0.2032 -0.3048)
							(mid 0.275042 -0.275042)
							(end 0.3048 -0.2032)
						)
					)
					(width 0)
					(fill yes)
				)
			)
		)
	)
	(footprint ""
		(layer "B.Cu")
		(at 96.497394 -53.160168 90)
		(property "Reference" "C94"
			(at 0 0 90)
			(layer "B.SilkS")
			(hide yes)
			(effects
				(font
					(size 1.27 1.27)
				)
				(justify mirror)
			)
		)
		(property "Value" "SCD01U16V1KX-GP"
			(at 2.8321 -1.7399 90)
			(unlocked yes)
			(layer "B.Fab")
			(hide yes)
			(effects
				(font
					(size 1.016 1.016)
					(thickness 0.1524)
				)
				(justify mirror)
			)
		)
		(property "Device Type" "C0201H13"
			(at 2.8321 -3.2639 90)
			(unlocked yes)
			(layer "B.Fab")
			(hide yes)
			(effects
				(font
					(size 1.016 1.016)
					(thickness 0.1524)
				)
				(justify mirror)
			)
		)
		(duplicate_pad_numbers_are_jumpers no)
		(fp_rect
			(start 0.2794 0.6477)
			(end -0.2794 -0.6477)
			(stroke
				(width 0)
				(type default)
			)
			(fill no)
			(layer "B.CrtYd")
		)
		(fp_rect
			(start 0.2794 0.6477)
			(end -0.2794 -0.6477)
			(stroke
				(width 0)
				(type default)
			)
			(fill no)
			(layer "B.Fab")
		)
		(pad "1" smd custom
			(at 0 -0.2794 270)
			(size 0.0762 0.0762)
			(layers "B.Cu" "B.Mask" "B.Paste")
			(net "PHY_DPB_TO_SCC_13_DP")
			(options
				(clearance outline)
				(anchor circle)
			)
			(primitives
				(gr_poly
					(pts
						(arc
							(start 0.1524 0.127)
							(mid 0.137521 0.162921)
							(end 0.1016 0.1778)
						)
						(arc
							(start -0.1016 0.1778)
							(mid -0.137521 0.162921)
							(end -0.1524 0.127)
						)
						(arc
							(start -0.1524 -0.127)
							(mid -0.137521 -0.162921)
							(end -0.1016 -0.1778)
						)
						(arc
							(start 0.1016 -0.1778)
							(mid 0.137521 -0.162921)
							(end 0.1524 -0.127)
						)
					)
					(width 0)
					(fill yes)
				)
			)
		)
		(pad "2" smd custom
			(at 0 0.2794 270)
			(size 0.0762 0.0762)
			(layers "B.Cu" "B.Mask" "B.Paste")
			(net "PHY_DPB_TO_SCC_C_13_DP")
			(options
				(clearance outline)
				(anchor circle)
			)
			(primitives
				(gr_poly
					(pts
						(arc
							(start 0.1524 0.127)
							(mid 0.137521 0.162921)
							(end 0.1016 0.1778)
						)
						(arc
							(start -0.1016 0.1778)
							(mid -0.137521 0.162921)
							(end -0.1524 0.127)
						)
						(arc
							(start -0.1524 -0.127)
							(mid -0.137521 -0.162921)
							(end -0.1016 -0.1778)
						)
						(arc
							(start 0.1016 -0.1778)
							(mid 0.137521 -0.162921)
							(end 0.1524 -0.127)
						)
					)
					(width 0)
					(fill yes)
				)
			)
		)
	)
)
